# BASEBOARD_FAB2 (Tioga Pass) — schematic netlist excerpt (pin names and nets, part order shuffled) for the footprints in the layout excerpt that follows; sources: Cadence DE-HDL packaged netlist, KiCad conversion of Wiwynn_Tioga_Pass_MB.brd

C4C14  SC1U10V2KX-4-GP  10%  pkg SMD-BCG6  page 204 : \1\ = P5V_STBY ; \2\ = GND
C9P4  CAP  10UF 16V 10% X6S  pkg 0805  page 208 : A = VR_FET_SW_P12V_STBY_PVCCIN_CPU1 ; B = GND
R2P21  RES  10.0K 1% CHIP  pkg 0402  page 196 : A = P3V3_STBY ; B = PWRGD_P5V_R

(kicad_pcb
	(version 20260206)
	(generator "pcbnew")
	(generator_version "10.0")
	(general
		(thickness 1.6)
		(legacy_teardrops no)
	)
	(paper "A4")
	(title_block
		(title "Wiwynn_Tioga_Pass_MB.brd")
		(comment 1 "Tioga Pass / footprints 4136-4138 of 4770")
	)
	(layers
		(0 "F.Cu" signal "TOP")
		(4 "In1.Cu" signal "L2GND")
		(6 "In2.Cu" signal "L3")
		(8 "In3.Cu" signal "L4GND")
		(10 "In4.Cu" signal "L5")
		(12 "In5.Cu" signal "L6GND")
		(14 "In6.Cu" signal "L7VCC")
		(16 "In7.Cu" signal "L8VCC")
		(18 "In8.Cu" signal "L9GND")
		(20 "In9.Cu" signal "L10")
		(22 "In10.Cu" signal "L11GND")
		(24 "In11.Cu" signal "L12")
		(26 "In12.Cu" signal "L13GND")
		(2 "B.Cu" signal "BOTTOM")
		(9 "F.Adhes" user "F.Adhesive")
		(11 "B.Adhes" user "B.Adhesive")
		(13 "F.Paste" user "Package Geometry/Pastemask Top")
		(15 "B.Paste" user "Package Geometry/Pastemask Bottom")
		(5 "F.SilkS" user "Ref Des/Silkscreen Top")
		(7 "B.SilkS" user "Ref Des/Silkscreen Bottom")
		(1 "F.Mask" user "Board Geometry/Soldermask Top")
		(3 "B.Mask" user "Board Geometry/Soldermask Bottom")
		(17 "Dwgs.User" user "User.Drawings")
		(19 "Cmts.User" user "User.Comments")
		(21 "Eco1.User" user "User.Eco1")
		(23 "Eco2.User" user "User.Eco2")
		(25 "Edge.Cuts" user "Board Geometry/Outline")
		(27 "Margin" user)
		(31 "F.CrtYd" user "Package Geometry/Place Bound Top")
		(29 "B.CrtYd" user "Package Geometry/Place Bound Bottom")
		(35 "F.Fab" user "Ref Des/Assembly Top")
		(33 "B.Fab" user "Ref Des/Assembly Bottom")
	)
	(footprint ""
		(layer "B.Cu")
		(at 32.832802 -74.553064 90)
		(property "Reference" "C9P4"
			(at 0 0 90)
			(layer "B.SilkS")
			(hide yes)
			(effects
				(font
					(size 1.27 1.27)
				)
				(justify mirror)
			)
		)
		(property "Value" ""
			(at 0 0 90)
			(layer "B.Fab")
			(effects
				(font
					(size 1.27 1.27)
				)
				(justify mirror)
			)
		)
		(duplicate_pad_numbers_are_jumpers no)
		(fp_poly
			(pts
				(xy 0.7239 -0.2159) (xy -0.7239 -0.2159) (xy -0.7239 1.9939) (xy 0.7239 1.9939)
			)
			(stroke
				(width 0)
				(type default)
			)
			(fill no)
			(layer "B.CrtYd")
		)
		(fp_line
			(start 0.7239 -0.2159)
			(end 0.7239 1.9939)
			(stroke
				(width 0.1)
				(type default)
			)
			(layer "B.Fab")
		)
		(fp_line
			(start -0.7239 -0.2159)
			(end 0.7239 -0.2159)
			(stroke
				(width 0.1)
				(type default)
			)
			(layer "B.Fab")
		)
		(fp_line
			(start 0.7239 1.9939)
			(end -0.7239 1.9939)
			(stroke
				(width 0.1)
				(type default)
			)
			(layer "B.Fab")
		)
		(fp_line
			(start -0.7239 1.9939)
			(end -0.7239 -0.2159)
			(stroke
				(width 0.1)
				(type default)
			)
			(layer "B.Fab")
		)
		(pad "1" smd rect
			(at 0 0 270)
			(size 1.27 1.016)
			(layers "B.Cu" "B.Mask" "B.Paste")
			(net "VR_FET_SW_P12V_STBY_PVCCIN_CPU1")
		)
		(pad "2" smd rect
			(at 0 1.778 270)
			(size 1.27 1.016)
			(layers "B.Cu" "B.Mask" "B.Paste")
			(net "GND")
		)
		(zone
			(layer "B.Cu")
			(hatch none 0.5)
			(connect_pads
				(clearance 0)
			)
			(min_thickness 0.25)
			(keepout
				(tracks not_allowed)
				(vias allowed)
				(pads allowed)
				(copperpour not_allowed)
				(footprints allowed)
			)
			(placement
				(enabled no)
				(sheetname "")
			)
			(fill
				(thermal_gap 0.5)
				(thermal_bridge_width 0.5)
				(island_removal_mode 0)
			)
			(polygon
				(pts
					(xy 33.340802 -75.188064) (xy 33.340802 -73.918064) (xy 34.102802 -73.918064) (xy 34.102802 -75.188064)
				)
			)
		)
	)
	(footprint ""
		(layer "B.Cu")
		(at 198.760588 -85.687662 90)
		(property "Reference" "C4C14"
			(at 0 0 90)
			(layer "B.SilkS")
			(hide yes)
			(effects
				(font
					(size 1.27 1.27)
				)
				(justify mirror)
			)
		)
		(property "Value" "*"
			(at -1.1811 -2.8194 90)
			(unlocked yes)
			(layer "B.Fab")
			(hide yes)
			(effects
				(font
					(size 1.27 1.016)
					(thickness 0.1524)
				)
				(justify mirror)
			)
		)
		(property "Device Type" "SC1U10V2KX-4-GP_SMD-BCG6-SC1U1A"
			(at -1.1811 -4.3434 90)
			(unlocked yes)
			(layer "B.Fab")
			(hide yes)
			(effects
				(font
					(size 1.27 1.016)
					(thickness 0.1524)
				)
				(justify mirror)
			)
		)
		(duplicate_pad_numbers_are_jumpers no)
		(fp_rect
			(start 0.4318 0.9525)
			(end -0.4318 -0.9525)
			(stroke
				(width 0)
				(type default)
			)
			(fill no)
			(layer "B.CrtYd")
		)
		(fp_rect
			(start 0.4318 0.9525)
			(end -0.4318 -0.9525)
			(stroke
				(width 0)
				(type default)
			)
			(fill no)
			(layer "B.Fab")
		)
		(pad "1" smd custom
			(at 0 -0.4445 270)
			(size 0.1524 0.1524)
			(layers "B.Cu" "B.Mask" "B.Paste")
			(net "P5V_STBY")
			(options
				(clearance outline)
				(anchor circle)
			)
			(primitives
				(gr_poly
					(pts
						(arc
							(start 0.3048 0.2032)
							(mid 0.275042 0.275042)
							(end 0.2032 0.3048)
						)
						(arc
							(start -0.2032 0.3048)
							(mid -0.275042 0.275042)
							(end -0.3048 0.2032)
						)
						(arc
							(start -0.3048 -0.2032)
							(mid -0.275042 -0.275042)
							(end -0.2032 -0.3048)
						)
						(arc
							(start 0.2032 -0.3048)
							(mid 0.275042 -0.275042)
							(end 0.3048 -0.2032)
						)
					)
					(width 0)
					(fill yes)
				)
			)
		)
		(pad "2" smd custom
			(at 0 0.4445 270)
			(size 0.1524 0.1524)
			(layers "B.Cu" "B.Mask" "B.Paste")
			(net "GND")
			(options
				(clearance outline)
				(anchor circle)
			)
			(primitives
				(gr_poly
					(pts
						(arc
							(start 0.3048 0.2032)
							(mid 0.275042 0.275042)
							(end 0.2032 0.3048)
						)
						(arc
							(start -0.2032 0.3048)
							(mid -0.275042 0.275042)
							(end -0.3048 0.2032)
						)
						(arc
							(start -0.3048 -0.2032)
							(mid -0.275042 -0.275042)
							(end -0.2032 -0.3048)
						)
						(arc
							(start 0.2032 -0.3048)
							(mid 0.275042 -0.275042)
							(end 0.3048 -0.2032)
						)
					)
					(width 0)
					(fill yes)
				)
			)
		)
	)
	(footprint ""
		(layer "B.Cu")
		(at 415.9885 -4.318 -90)
		(property "Reference" "R2P21"
			(at 0 0 90)
			(layer "B.SilkS")
			(hide yes)
			(effects
				(font
					(size 1.27 1.27)
				)
				(justify mirror)
			)
		)
		(property "Value" ""
			(at 0 0 90)
			(layer "B.Fab")
			(effects
				(font
					(size 1.27 1.27)
				)
				(justify mirror)
			)
		)
		(duplicate_pad_numbers_are_jumpers no)
		(fp_poly
			(pts
				(xy 0.2794 -0.1016) (xy -0.2794 -0.1016) (xy -0.2794 0.9906) (xy 0.2794 0.9906)
			)
			(stroke
				(width 0)
				(type default)
			)
			(fill no)
			(layer "B.CrtYd")
		)
		(fp_line
			(start -0.2794 0.9906)
			(end -0.2794 -0.1016)
			(stroke
				(width 0.1)
				(type default)
			)
			(layer "B.Fab")
		)
		(fp_line
			(start 0.2794 0.9906)
			(end -0.2794 0.9906)
			(stroke
				(width 0.1)
				(type default)
			)
			(layer "B.Fab")
		)
		(fp_line
			(start -0.2794 -0.1016)
			(end 0.2794 -0.1016)
			(stroke
				(width 0.1)
				(type default)
			)
			(layer "B.Fab")
		)
		(fp_line
			(start 0.2794 -0.1016)
			(end 0.2794 0.9906)
			(stroke
				(width 0.1)
				(type default)
			)
			(layer "B.Fab")
		)
		(pad "1" smd rect
			(at 0 0 90)
			(size 0.508 0.508)
			(layers "B.Cu" "B.Mask" "B.Paste")
			(net "P3V3_STBY")
		)
		(pad "2" smd rect
			(at 0 0.889 90)
			(size 0.508 0.508)
			(layers "B.Cu" "B.Mask" "B.Paste")
			(net "PWRGD_P5V_R")
		)
		(zone
			(layer "B.Cu")
			(hatch none 0.5)
			(connect_pads
				(clearance 0)
			)
			(min_thickness 0.25)
			(keepout
				(tracks not_allowed)
				(vias allowed)
				(pads allowed)
				(copperpour not_allowed)
				(footprints allowed)
			)
			(placement
				(enabled no)
				(sheetname "")
			)
			(fill
				(thermal_gap 0.5)
				(thermal_bridge_width 0.5)
				(island_removal_mode 0)
			)
			(polygon
				(pts
					(xy 415.3535 -4.064) (xy 415.3535 -4.572) (xy 415.7345 -4.572) (xy 415.7345 -4.064)
				)
			)
		)
		(zone
			(layer "B.Cu")
			(hatch none 0.5)
			(connect_pads
				(clearance 0)
			)
			(min_thickness 0.25)
			(keepout
				(tracks allowed)
				(vias not_allowed)
				(pads allowed)
				(copperpour not_allowed)
				(footprints allowed)
			)
			(placement
				(enabled no)
				(sheetname "")
			)
			(fill
				(thermal_gap 0.5)
				(thermal_bridge_width 0.5)
				(island_removal_mode 0)
			)
			(polygon
				(pts
					(xy 415.7345 -4.064) (xy 415.7345 -4.572) (xy 415.3535 -4.572) (xy 415.3535 -4.064)
				)
			)
		)
	)
)
